(kicad_pcb
	(version 20241229)
	(generator "pcbnew")
	(generator_version "9.0")
	(general
		(thickness 1.6296)
		(legacy_teardrops no)
	)
	(paper "A3")
	(title_block
		(title "Thunderbolt to 10GbE adapter")
		(date "2026-04-21")
		(rev "1.1.0")
		(company "Antmicro Ltd")
		(comment 1 "www.antmicro.com")
		(comment 9 "footprints 236-237 of 703")
	)
	(layers
		(0 "F.Cu" signal)
		(4 "In1.Cu" signal)
		(6 "In2.Cu" signal)
		(8 "In3.Cu" signal)
		(10 "In4.Cu" signal)
		(12 "In5.Cu" signal)
		(14 "In6.Cu" signal)
		(2 "B.Cu" signal)
		(9 "F.Adhes" user "F.Adhesive")
		(11 "B.Adhes" user "B.Adhesive")
		(13 "F.Paste" user)
		(15 "B.Paste" user)
		(5 "F.SilkS" user "F.Silkscreen")
		(7 "B.SilkS" user "B.Silkscreen")
		(1 "F.Mask" user)
		(3 "B.Mask" user)
		(17 "Dwgs.User" user "User.Drawings")
		(19 "Cmts.User" user "User.Comments")
		(21 "Eco1.User" user "User.Eco1")
		(23 "Eco2.User" user "User.Eco2")
		(25 "Edge.Cuts" user)
		(27 "Margin" user)
		(31 "F.CrtYd" user "F.Courtyard")
		(29 "B.CrtYd" user "B.Courtyard")
		(35 "F.Fab" user)
		(33 "B.Fab" user)
	)
	(footprint "antmicro-footprints:MLP44-24L_4x4x0.75mm"
		(layer "F.Cu")
		(at 158 50.2)
		(property "Reference" "U20"
			(at -4.8 2.4 0)
			(layer "F.SilkS")
			(effects
				(font
					(size 0.7 0.7)
					(thickness 0.15)
				)
				(justify left bottom)
			)
		)
		(property "Value" "SIC437AED-T1-GE3"
			(at -2.7 3.6 0)
			(layer "F.Fab")
			(effects
				(font
					(size 0.7 0.7)
					(thickness 0.15)
				)
				(justify left bottom)
			)
		)
		(property "Datasheet" "https://www.vishay.com/docs/75921/sic437.pdf"
			(at 0 0 0)
			(layer "F.Fab")
			(hide yes)
			(effects
				(font
					(size 1.27 1.27)
					(thickness 0.15)
				)
			)
		)
		(property "Description" "DC/DC Buck Step Down Regulator Adjustable, 4.5-28V In, 0.6V to 20V/12A Out, 1MHz, PowerPAK MLP44-24"
			(at 0 0 0)
			(layer "F.Fab")
			(hide yes)
			(effects
				(font
					(size 1.27 1.27)
					(thickness 0.15)
				)
			)
		)
		(property "Manufacturer" "Vishay"
			(at 0 0 0)
			(unlocked yes)
			(layer "F.Fab")
			(hide yes)
			(effects
				(font
					(size 1 1)
					(thickness 0.15)
				)
			)
		)
		(property "MPN" "SIC437AED-T1-GE3"
			(at 0 0 0)
			(unlocked yes)
			(layer "F.Fab")
			(hide yes)
			(effects
				(font
					(size 1 1)
					(thickness 0.15)
				)
			)
		)
		(property "Author" "Antmicro"
			(at 0 0 0)
			(unlocked yes)
			(layer "F.Fab")
			(hide yes)
			(effects
				(font
					(size 1 1)
					(thickness 0.15)
				)
			)
		)
		(property "License" "Apache-2.0"
			(at 0 0 0)
			(unlocked yes)
			(layer "F.Fab")
			(hide yes)
			(effects
				(font
					(size 1 1)
					(thickness 0.15)
				)
			)
		)
		(sheetname "/Power input/")
		(sheetfile "power_input.kicad_sch")
		(attr smd)
		(net_tie_pad_groups "1,2,26" "3,4,27" "5,6,7,8,9")
		(fp_line
			(start -2.11 -1.38)
			(end -2.11 -2.1)
			(stroke
				(width 0.15)
				(type solid)
			)
			(layer "F.SilkS")
		)
		(fp_line
			(start -2.11 2.11)
			(end -2.11 1.39)
			(stroke
				(width 0.15)
				(type solid)
			)
			(layer "F.SilkS")
		)
		(fp_line
			(start -1.89 -2.1)
			(end -2.11 -2.1)
			(stroke
				(width 0.15)
				(type solid)
			)
			(layer "F.SilkS")
		)
		(fp_line
			(start -1.89 2.11)
			(end -2.11 2.11)
			(stroke
				(width 0.15)
				(type solid)
			)
			(layer "F.SilkS")
		)
		(fp_line
			(start 1.44 2.11)
			(end 2.11 2.11)
			(stroke
				(width 0.15)
				(type solid)
			)
			(layer "F.SilkS")
		)
		(fp_line
			(start 1.89 -2.11)
			(end 2.11 -2.11)
			(stroke
				(width 0.15)
				(type solid)
			)
			(layer "F.SilkS")
		)
		(fp_line
			(start 2.11 -2.11)
			(end 2.11 -1.69)
			(stroke
				(width 0.15)
				(type solid)
			)
			(layer "F.SilkS")
		)
		(fp_line
			(start 2.11 2.11)
			(end 2.11 1.84)
			(stroke
				(width 0.15)
				(type solid)
			)
			(layer "F.SilkS")
		)
		(fp_circle
			(center -2.25 -1.15)
			(end -2.2 -1.15)
			(stroke
				(width 0.15)
				(type solid)
			)
			(fill yes)
			(layer "F.SilkS")
		)
		(fp_line
			(start -2.55 -2.55)
			(end 2.55 -2.55)
			(stroke
				(width 0.05)
				(type solid)
			)
			(layer "F.CrtYd")
		)
		(fp_line
			(start -2.55 2.55)
			(end -2.55 -2.55)
			(stroke
				(width 0.05)
				(type solid)
			)
			(layer "F.CrtYd")
		)
		(fp_line
			(start 2.55 -2.55)
			(end 2.55 2.55)
			(stroke
				(width 0.05)
				(type solid)
			)
			(layer "F.CrtYd")
		)
		(fp_line
			(start 2.55 2.55)
			(end -2.55 2.55)
			(stroke
				(width 0.05)
				(type solid)
			)
			(layer "F.CrtYd")
		)
		(fp_line
			(start -2 -1)
			(end -2 2)
			(stroke
				(width 0.15)
				(type solid)
			)
			(layer "F.Fab")
		)
		(fp_line
			(start -2 2)
			(end 2 2)
			(stroke
				(width 0.15)
				(type solid)
			)
			(layer "F.Fab")
		)
		(fp_line
			(start -1 -2)
			(end -2 -1)
			(stroke
				(width 0.15)
				(type solid)
			)
			(layer "F.Fab")
		)
		(fp_line
			(start 2 -2)
			(end -1 -2)
			(stroke
				(width 0.15)
				(type solid)
			)
			(layer "F.Fab")
		)
		(fp_line
			(start 2 2)
			(end 2 -2)
			(stroke
				(width 0.15)
				(type solid)
			)
			(layer "F.Fab")
		)
		(fp_text user "${REFERENCE}"
			(at -2.7 6.8 0)
			(layer "F.Fab")
			(effects
				(font
					(size 0.7 0.7)
					(thickness 0.15)
				)
				(justify left bottom)
			)
		)
		(fp_text user "License: Apache-2.0"
			(at -2.7 5.6 0)
			(layer "F.Fab")
			(effects
				(font
					(size 0.7 0.7)
					(thickness 0.15)
				)
				(justify left bottom)
			)
		)
		(fp_text user "Author: Antmicro"
			(at -2.7 8 0)
			(layer "F.Fab")
			(effects
				(font
					(size 0.7 0.7)
					(thickness 0.15)
				)
				(justify left bottom)
			)
		)
		(pad "1" smd roundrect
			(at -1.94 -0.825 90)
			(size 0.3 0.725)
			(layers "F.Cu" "F.Mask" "F.Paste")
			(roundrect_rratio 0.25)
			(net 412 "Net-(D15-C)")
			(pinfunction "V_{IN}")
			(pintype "power_in")
		)
		(pad "2" smd roundrect
			(at -1.94 -0.375 90)
			(size 0.3 0.725)
			(layers "F.Cu" "F.Mask" "F.Paste")
			(roundrect_rratio 0.25)
			(net 412 "Net-(D15-C)")
			(pinfunction "V_{IN}")
			(pintype "passive")
		)
		(pad "3" smd roundrect
			(at -1.94 0.525 90)
			(size 0.3 0.725)
			(layers "F.Cu" "F.Mask" "F.Paste")
			(roundrect_rratio 0.25)
			(net 23 "GND")
			(pinfunction "P_{GND}")
			(pintype "passive")
		)
		(pad "4" smd roundrect
			(at -1.94 0.975 90)
			(size 0.3 0.725)
			(layers "F.Cu" "F.Mask" "F.Paste")
			(roundrect_rratio 0.25)
			(net 23 "GND")
			(pinfunction "P_{GND}")
			(pintype "passive")
		)
		(pad "5" smd custom
			(at -1.475 1.94)
			(size 0.3 0.3)
			(layers "F.Cu" "F.Mask" "F.Paste")
			(net 354 "/Power input/5V_SW")
			(pinfunction "SW")
			(pintype "passive")
			(options
				(clearance outline)
				(anchor circle)
			)
			(primitives
				(gr_poly
					(pts
						(xy -0.15 -0.2875) (xy -0.144291 -0.316201) (xy -0.128033 -0.340533) (xy -0.103701 -0.356791)
						(xy -0.075 -0.3625) (xy 0.075 -0.3625) (xy 0.103701 -0.356791) (xy 0.128033 -0.340533) (xy 0.144291 -0.316201)
						(xy 0.15 -0.2875) (xy 0.15 0.2875) (xy 0.144291 0.316201) (xy 0.128033 0.340533) (xy 0.103701 0.356791)
						(xy 0.075 0.3625) (xy -0.075 0.3625) (xy -0.103701 0.356791) (xy -0.128033 0.340533) (xy -0.144291 0.316201)
						(xy -0.15 0.2875)
					)
					(width 0)
					(fill yes)
				)
				(gr_poly
					(pts
						(xy -0.15 -0.3625) (xy 2.2 -0.3625) (xy 2.2 -0.0875) (xy -0.15 -0.0875)
					)
					(width 0)
					(fill yes)
				)
			)
		)
		(pad "6" smd roundrect
			(at -1.025 1.94)
			(size 0.3 0.725)
			(layers "F.Cu" "F.Mask" "F.Paste")
			(roundrect_rratio 0.25)
			(net 354 "/Power input/5V_SW")
			(pinfunction "SW")
			(pintype "passive")
		)
		(pad "7" smd roundrect
			(at -0.575 1.94)
			(size 0.3 0.725)
			(layers "F.Cu" "F.Mask" "F.Paste")
			(roundrect_rratio 0.25)
			(net 354 "/Power input/5V_SW")
			(pinfunction "SW")
			(pintype "passive")
		)
		(pad "8" smd roundrect
			(at 0.125 1.94)
			(size 0.3 0.725)
			(layers "F.Cu" "F.Mask" "F.Paste")
			(roundrect_rratio 0.25)
			(net 354 "/Power input/5V_SW")
			(pinfunction "SW")
			(pintype "passive")
		)
		(pad "9" smd roundrect
			(at 0.575 1.94)
			(size 0.3 0.725)
			(layers "F.Cu" "F.Mask" "F.Paste")
			(roundrect_rratio 0.25)
			(net 354 "/Power input/5V_SW")
			(pinfunction "SW")
			(pintype "passive")
		)
		(pad "10" smd roundrect
			(at 1.025 1.935)
			(size 0.3 0.725)
			(layers "F.Cu" "F.Mask" "F.Paste")
			(roundrect_rratio 0.25)
			(net 591 "unconnected-(U20-GL-Pad10)_2")
			(pinfunction "GL")
			(pintype "passive+no_connect")
		)
		(pad "11" smd roundrect
			(at 1.94 1.425 90)
			(size 0.3 0.725)
			(layers "F.Cu" "F.Mask" "F.Paste")
			(roundrect_rratio 0.25)
			(net 590 "unconnected-(U20-GL-Pad10)_1")
			(pinfunction "GL")
			(pintype "passive+no_connect")
		)
		(pad "12" smd roundrect
			(at 1.94 0.975 90)
			(size 0.3 0.725)
			(layers "F.Cu" "F.Mask" "F.Paste")
			(roundrect_rratio 0.25)
			(net 346 "/Power input/5V_VDRV")
			(pinfunction "V_{DRV}")
			(pintype "passive")
		)
		(pad "13" smd roundrect
			(at 1.94 0.525 90)
			(size 0.3 0.725)
			(layers "F.Cu" "F.Mask" "F.Paste")
			(roundrect_rratio 0.25)
			(net 23 "GND")
			(pinfunction "P_{GND}")
			(pintype "power_in")
		)
		(pad "14" smd roundrect
			(at 1.94 0.075 90)
			(size 0.3 0.725)
			(layers "F.Cu" "F.Mask" "F.Paste")
			(roundrect_rratio 0.25)
			(net 592 "unconnected-(U20-P_{GOOD}-Pad14)")
			(pinfunction "P_{GOOD}")
			(pintype "output+no_connect")
		)
		(pad "15" smd roundrect
			(at 1.94 -0.375 90)
			(size 0.3 0.725)
			(layers "F.Cu" "F.Mask" "F.Paste")
			(roundrect_rratio 0.25)
			(net 345 "/Power input/5V_VDD")
			(pinfunction "V_{DD}")
			(pintype "passive")
		)
		(pad "16" smd roundrect
			(at 1.94 -0.825 90)
			(size 0.3 0.725)
			(layers "F.Cu" "F.Mask" "F.Paste")
			(roundrect_rratio 0.25)
			(net 23 "GND")
			(pinfunction "A_{GND}")
			(pintype "power_in")
		)
		(pad "17" smd roundrect
			(at 1.94 -1.275 90)
			(size 0.3 0.725)
			(layers "F.Cu" "F.Mask" "F.Paste")
			(roundrect_rratio 0.25)
			(net 391 "/Power input/5V_FB")
			(pinfunction "FB")
			(pintype "passive")
		)
		(pad "18" smd roundrect
			(at 1.475 -1.94)
			(size 0.3 0.725)
			(layers "F.Cu" "F.Mask" "F.Paste")
			(roundrect_rratio 0.25)
			(net 349 "/Power input/5V_OUT")
			(pinfunction "V_{OUT}")
			(pintype "passive")
		)
		(pad "19" smd roundrect
			(at 1.025 -1.94)
			(size 0.3 0.725)
			(layers "F.Cu" "F.Mask" "F.Paste")
			(roundrect_rratio 0.25)
			(net 344 "/Power input/5V_EN")
			(pinfunction "EN")
			(pintype "input")
		)
		(pad "20" smd roundrect
			(at 0.575 -1.94)
			(size 0.3 0.725)
			(layers "F.Cu" "F.Mask" "F.Paste")
			(roundrect_rratio 0.25)
			(net 390 "/Power input/5V_MODE2")
			(pinfunction "MODE2")
			(pintype "input")
		)
		(pad "21" smd roundrect
			(at 0.125 -1.94)
			(size 0.3 0.725)
			(layers "F.Cu" "F.Mask" "F.Paste")
			(roundrect_rratio 0.25)
			(net 389 "/Power input/5V_MODE1")
			(pinfunction "MODE1")
			(pintype "input")
		)
		(pad "22" smd roundrect
			(at -0.575 -1.94)
			(size 0.3 0.725)
			(layers "F.Cu" "F.Mask" "F.Paste")
			(roundrect_rratio 0.25)
			(net 412 "Net-(D15-C)")
			(pinfunction "V_{IN}")
			(pintype "passive")
		)
		(pad "23" smd roundrect
			(at -1.025 -1.94)
			(size 0.3 0.725)
			(layers "F.Cu" "F.Mask" "F.Paste")
			(roundrect_rratio 0.25)
			(net 347 "/Power input/5V_BOOT")
			(pinfunction "BOOT")
			(pintype "passive")
		)
		(pad "24" smd roundrect
			(at -1.475 -1.94)
			(size 0.3 0.725)
			(layers "F.Cu" "F.Mask" "F.Paste")
			(roundrect_rratio 0.25)
			(net 348 "/Power input/5V_PHASE")
			(pinfunction "PHASE")
			(pintype "passive")
		)
		(pad "25" smd rect
			(at 0.49 -0.75 180)
			(size 1.575 1.05)
			(layers "F.Cu" "F.Mask" "F.Paste")
			(net 23 "GND")
			(pinfunction "A_{GND}")
			(pintype "passive")
		)
		(pad "26" smd rect
			(at -1.175 -0.75 180)
			(size 1.15 1.05)
			(layers "F.Cu" "F.Mask" "F.Paste")
			(net 412 "Net-(D15-C)")
			(pinfunction "V_{IN}")
			(pintype "passive")
		)
		(pad "27" smd custom
			(at -0.75 0.775)
			(size 1 1)
			(layers "F.Cu" "F.Mask" "F.Paste")
			(net 23 "GND")
			(pinfunction "P_{GND}")
			(pintype "passive")
			(options
				(clearance outline)
				(anchor rect)
			)
			(primitives
				(gr_poly
					(pts
						(xy -1 0.5) (xy -1 -0.7) (xy 1.825 -0.7) (xy 1.825 -0.245) (xy 1.175 -0.245) (xy 1.175 0.5)
					)
					(width 0)
					(fill yes)
				)
			)
		)
		(pad "28" smd rect
			(at 0.985 0.99 180)
			(size 0.58 0.38)
			(layers "F.Cu" "F.Mask" "F.Paste")
			(net 589 "unconnected-(U20-GL-Pad10)")
			(pinfunction "GL")
			(pintype "passive+no_connect")
		)
	)
	(footprint "antmicro-footprints:C_0402_1005Metric"
		(layer "F.Cu")
		(at 124 73 180)
		(descr "Capacitor SMD 0402")
		(tags "capacitor SMD 0402")
		(property "Reference" "C309"
			(at -1 0.4 180)
			(layer "F.SilkS")
			(effects
				(font
					(size 0.7 0.7)
					(thickness 0.15)
				)
				(justify left bottom)
			)
		)
		(property "Value" "C_470p_0402"
			(at -1.022927 2.155213 180)
			(layer "F.Fab")
			(effects
				(font
					(size 0.7 0.7)
					(thickness 0.15)
				)
				(justify left bottom)
			)
		)
		(property "Datasheet" "https://www.passivecomponent.com/wp-content/uploads/datasheet/WTC_MLCC_General_Purpose.pdf"
			(at 0 0 180)
			(layer "F.Fab")
			(hide yes)
			(effects
				(font
					(size 1.27 1.27)
					(thickness 0.15)
				)
			)
		)
		(property "Description" "SMD Multilayer Ceramic Capacitor, General Purpose, 470 pF, 25 V, 0402 [1005 Metric], ± 10%, X7R"
			(at 0 0 180)
			(layer "F.Fab")
			(hide yes)
			(effects
				(font
					(size 1.27 1.27)
					(thickness 0.15)
				)
			)
		)
		(property "MPN" "0402B471K250CT"
			(at 0 0 180)
			(unlocked yes)
			(layer "F.Fab")
			(hide yes)
			(effects
				(font
					(size 1 1)
					(thickness 0.15)
				)
			)
		)
		(property "Manufacturer" "Walsin"
			(at 0 0 180)
			(unlocked yes)
			(layer "F.Fab")
			(hide yes)
			(effects
				(font
					(size 1 1)
					(thickness 0.15)
				)
			)
		)
		(property "License" "Apache-2.0"
			(at 0 0 180)
			(unlocked yes)
			(layer "F.Fab")
			(hide yes)
			(effects
				(font
					(size 1 1)
					(thickness 0.15)
				)
			)
		)
		(property "Author" "Antmicro"
			(at 0 0 180)
			(unlocked yes)
			(layer "F.Fab")
			(hide yes)
			(effects
				(font
					(size 1 1)
					(thickness 0.15)
				)
			)
		)
		(property "Val" "470p"
			(at 0 0 180)
			(unlocked yes)
			(layer "F.Fab")
			(hide yes)
			(effects
				(font
					(size 1 1)
					(thickness 0.15)
				)
			)
		)
		(property "Voltage" "25V"
			(at 0 0 180)
			(unlocked yes)
			(layer "F.Fab")
			(hide yes)
			(effects
				(font
					(size 1 1)
					(thickness 0.15)
				)
			)
		)
		(property "Dielectric" "X7R"
			(at 0 0 180)
			(unlocked yes)
			(layer "F.Fab")
			(hide yes)
			(effects
				(font
					(size 1 1)
					(thickness 0.15)
				)
			)
		)
		(sheetname "/Fan controller/")
		(sheetfile "fan-controller.kicad_sch")
		(attr smd)
		(fp_rect
			(start -0.925 -0.47)
			(end 0.925 0.47)
			(stroke
				(width 0.05)
				(type default)
			)
			(fill no)
			(layer "F.CrtYd")
		)
		(fp_line
			(start 0.504 0.248)
			(end -0.494 0.248)
			(stroke
				(width 0.15)
				(type solid)
			)
			(layer "F.Fab")
		)
		(fp_line
			(start 0.504 -0.25)
			(end 0.504 0.248)
			(stroke
				(width 0.15)
				(type solid)
			)
			(layer "F.Fab")
		)
		(fp_line
			(start -0.494 0.248)
			(end -0.494 -0.25)
			(stroke
				(width 0.15)
				(type solid)
			)
			(layer "F.Fab")
		)
		(fp_line
			(start -0.494 -0.25)
			(end 0.504 -0.25)
			(stroke
				(width 0.15)
				(type solid)
			)
			(layer "F.Fab")
		)
		(fp_text user "License: Apache-2.0"
			(at -0.939 5.799 180)
			(layer "F.Fab")
			(effects
				(font
					(size 0.7 0.7)
					(thickness 0.15)
				)
				(justify left bottom)
			)
		)
		(fp_text user "${REFERENCE}"
			(at -0.939 4.599 180)
			(layer "F.Fab")
			(effects
				(font
					(size 0.7 0.7)
					(thickness 0.15)
				)
				(justify left bottom)
			)
		)
		(fp_text user "Author: Antmicro"
			(at -0.939 3.399 180)
			(layer "F.Fab")
			(effects
				(font
					(size 0.7 0.7)
					(thickness 0.15)
				)
				(justify left bottom)
			)
		)
		(pad "1" smd roundrect
			(at -0.48 0 180)
			(size 0.59 0.64)
			(layers "F.Cu" "F.Mask" "F.Paste")
			(roundrect_rratio 0.25)
			(net 23 "GND")
			(pintype "passive")
		)
		(pad "2" smd roundrect
			(at 0.48 0 180)
			(size 0.59 0.64)
			(layers "F.Cu" "F.Mask" "F.Paste")
			(roundrect_rratio 0.25)
			(net 152 "/Fan controller/FREQ")
			(pintype "passive")
		)
	)
)
